# T6G (Grand Teton) — schematic parts with pin connectivity, parts 2568–2596 of 8303; source: Cadence DE-HDL packaged netlist (pstxprt.dat, pstxnet.dat, pstchip.dat)

H99  HOLE  EMPTY  pkg TH  page 230 : 1 = GND
H100  HOLE  EMPTY  pkg TH  page 230 : 1 = GND
H101  HOLE  EMPTY  pkg TH  page 230 : 1 = GND
H102  HOLE  EMPTY  pkg TH  page 230 : 1 = GND
H103  HOLE  EMPTY  pkg TH  page 230 : 1 = GND
H104  HOLE  EMPTY  pkg TH  page 230 : 1 = GND
H105  HOLE  EMPTY  pkg TH  page 230 : 1 = GND
H106  HOLE  EMPTY  pkg TH  page 230 : 1 = GND

H111  GND_HOLE  EMPTY  pkg TH  page 230
  2  GND2  POWER  = GND
  3  GND3  POWER  = GND
  4  GND4  POWER  = GND
  5  GND5  POWER  = GND
  6  GND6  POWER  = GND
  7  GND7  POWER  = GND
  8  GND8  POWER  = GND
  9  GND9  POWER  = GND

H112  GND_HOLE  EMPTY  pkg TH  page 230
  2  GND2  POWER  = GND
  3  GND3  POWER  = GND
  4  GND4  POWER  = GND
  5  GND5  POWER  = GND
  6  GND6  POWER  = GND
  7  GND7  POWER  = GND
  8  GND8  POWER  = GND
  9  GND9  POWER  = GND

H113  GND_HOLE  EMPTY  pkg TH  page 230
  2  GND2  POWER  = GND
  3  GND3  POWER  = GND
  4  GND4  POWER  = GND
  5  GND5  POWER  = GND
  6  GND6  POWER  = GND
  7  GND7  POWER  = GND
  8  GND8  POWER  = GND
  9  GND9  POWER  = GND

H114  GND_HOLE  EMPTY  pkg TH  page 230
  2  GND2  POWER  = GND
  3  GND3  POWER  = GND
  4  GND4  POWER  = GND
  5  GND5  POWER  = GND
  6  GND6  POWER  = GND
  7  GND7  POWER  = GND
  8  GND8  POWER  = GND
  9  GND9  POWER  = GND

H115  GND_HOLE  EMPTY  pkg TH  page 230
  2  GND2  POWER  = GND
  3  GND3  POWER  = GND
  4  GND4  POWER  = GND
  5  GND5  POWER  = GND
  6  GND6  POWER  = GND
  7  GND7  POWER  = GND
  8  GND8  POWER  = GND
  9  GND9  POWER  = GND

H124  HOLE  EMPTY  pkg TH  page 230 : 1 = NC
H125  HOLE  EMPTY  pkg TH  page 230 : 1 = NC
H126  HOLE  EMPTY  pkg TH  page 230 : 1 = NC
H127  HOLE  EMPTY  pkg TH  page 230 : 1 = NC
H128  HOLE  EMPTY  pkg TH  page 230 : 1 = GND
H6000  HOLE  EMPTY  pkg TH  page 230 : 1 = GND
H6001  HOLE  EMPTY  pkg TH  page 230 : 1 = GND
H6002  HOLE  EMPTY  pkg TH  page 230 : 1 = GND
H8027  HOLE  EMPTY  pkg TH  page 230 : 1 = GND
H8028  HOLE  EMPTY  pkg TH  page 230 : 1 = GND

J1  SCONN288_DDR506112002KQ  IO  pkg DDR288S_1-1VXC  page 86
  1  VIN_BULK0  POWER  = P12V_MEM_CPU0
  2  RFU0  TRI  = NC
  3  VIN_MGMT  POWER  = P3V3_AUX
  4  HSCL  IN  = I3C_SPD_DDRA_CPU0_SCL
  5  HSDA  BI  = I3C_SPD_DDRA_CPU0_SDA
  6  VSS0  POWER  = GND
  7  DQ0_A  BI  = M_A_CPU0_SA_DQ<0>
  8  VSS1  POWER  = GND
  9  DQ1_A  BI  = M_A_CPU0_SA_DQ<1>
  10  VSS2  POWER  = GND
  11  DQS0_A_T  BI  = M_A_CPU0_SA_DQS_DP<0>
  12  DQS0_A_C  BI  = M_A_CPU0_SA_DQS_DN<0>
  13  VSS3  POWER  = GND
  14  DQ4_A  BI  = M_A_CPU0_SA_DQ<4>
  15  VSS4  POWER  = GND
  16  DQ5_A  BI  = M_A_CPU0_SA_DQ<5>
  17  VSS5  POWER  = GND
  18  DQ8_A  BI  = M_A_CPU0_SA_DQ<8>
  19  VSS6  POWER  = GND
  20  DQ9_A  BI  = M_A_CPU0_SA_DQ<9>
  21  VSS7  POWER  = GND
  22  DQS1_A_T  BI  = M_A_CPU0_SA_DQS_DP<1>
  23  DQS1_A_C  BI  = M_A_CPU0_SA_DQS_DN<1>
  24  VSS8  POWER  = GND
  25  DQ12_A  BI  = M_A_CPU0_SA_DQ<12>
  26  VSS9  POWER  = GND
  27  DQ13_A  BI  = M_A_CPU0_SA_DQ<13>
  28  VSS10  POWER  = GND
  29  DQ16_A  BI  = M_A_CPU0_SA_DQ<16>
  30  VSS11  POWER  = GND
  31  DQ17_A  BI  = M_A_CPU0_SA_DQ<17>
  32  VSS12  POWER  = GND
  33  DQS2_A_T  BI  = M_A_CPU0_SA_DQS_DP<2>
  34  DQS2_A_C  BI  = M_A_CPU0_SA_DQS_DN<2>
  35  VSS13  POWER  = GND
  36  DQ20_A  BI  = M_A_CPU0_SA_DQ<20>
  37  VSS14  POWER  = GND
  38  DQ21_A  BI  = M_A_CPU0_SA_DQ<21>
  39  VSS15  POWER  = GND
  40  DQ24_A  BI  = M_A_CPU0_SA_DQ<24>
  41  VSS16  POWER  = GND
  42  DQ25_A  BI  = M_A_CPU0_SA_DQ<25>
  43  VSS17  POWER  = GND
  44  DQS3_A_T  BI  = M_A_CPU0_SA_DQS_DP<3>
  45  DQS3_A_C  BI  = M_A_CPU0_SA_DQS_DN<3>
  46  VSS18  POWER  = GND
  47  DQ28_A  BI  = M_A_CPU0_SA_DQ<28>
  48  VSS19  POWER  = GND
  49  DQ29_A  BI  = M_A_CPU0_SA_DQ<29>
  50  VSS20  POWER  = GND
  51  CB0_A  BI  = M_A_CPU0_SA_CB<0>
  52  VSS21  POWER  = GND
  53  CB1_A  BI  = M_A_CPU0_SA_CB<1>
  54  VSS22  POWER  = GND
  55  DQS4_A_T  BI  = M_A_CPU0_SA_DQS_DP<4>
  56  DQS4_A_C  BI  = M_A_CPU0_SA_DQS_DN<4>
  57  VSS23  POWER  = GND
  58  CB4_A  BI  = M_A_CPU0_SA_CB<4>
  59  VSS24  POWER  = GND
  60  CB5_A  BI  = M_A_CPU0_SA_CB<5>
  61  VSS25  POWER  = GND
  62  ALERT_N  OUT  = M_A_CPU0_ALERT_N
  63  VSS26  POWER  = GND
  64  CS0_A_N  IN  = M_A_CPU0_SA_CS_N<0>
  65  VSS27  POWER  = GND
  66  CA0_A  IN  = M_A_CPU0_SA_CA<0>
  67  VSS28  POWER  = GND
  68  CA2_A  IN  = M_A_CPU0_SA_CA<2>
  69  VSS29  POWER  = GND
  70  CA4_A  IN  = M_A_CPU0_SA_CA<4>
  71  VSS30  POWER  = GND
  72  CA6_A  IN  = M_A_CPU0_SA_CA<6>
  73  VSS31  POWER  = GND
  74  PAR_A  IN  = M_A_CPU0_SA_PAR
  75  VSS32  POWER  = GND
  76  CA0_B  IN  = M_A_CPU0_SB_CA<0>
  77  VSS33  POWER  = GND
  78  CA2_B  IN  = M_A_CPU0_SB_CA<2>
  79  VSS34  POWER  = GND
  80  CA4_B  IN  = M_A_CPU0_SB_CA<4>
  81  VSS35  POWER  = GND
  82  CA6_B  IN  = M_A_CPU0_SB_CA<6>
  83  VSS36  POWER  = GND
  84  CS0_B_N  IN  = M_A_CPU0_SB_CS_N<0>
  85  VSS37  POWER  = GND
  86  \lbd||rsp_a_n\  OUT  = M_A_CPU0_SA_RSP<0>
  87  \lbs||rsp_b_n\  OUT  = M_A_CPU0_SB_RSP<0>
  88  VSS38  POWER  = GND
  89  CB4_B  BI  = M_A_CPU0_SB_CB<4>
  90  VSS39  POWER  = GND
  91  CB5_B  BI  = M_A_CPU0_SB_CB<5>
  92  VSS40  POWER  = GND
  93  \dqs9_b_t||tdqs9_b_t||dbi4_b_n\  BI  = M_A_CPU0_SB_DQS_DP<9>
  94  \dqs9_b_c||tdqs9_b_c\  BI  = M_A_CPU0_SB_DQS_DN<9>
  95  VSS41  POWER  = GND
  96  CB0_B  BI  = M_A_CPU0_SB_CB<0>
  97  VSS42  POWER  = GND
  98  CB1_B  BI  = M_A_CPU0_SB_CB<1>
  99  VSS43  POWER  = GND
  100  DQ0_B  BI  = M_A_CPU0_SB_DQ<0>
  101  VSS44  POWER  = GND
  102  DQ1_B  BI  = M_A_CPU0_SB_DQ<1>
  103  VSS45  POWER  = GND
  104  DQS0_B_T  BI  = M_A_CPU0_SB_DQS_DP<0>
  105  DQS0_B_C  BI  = M_A_CPU0_SB_DQS_DN<0>
  106  VSS46  POWER  = GND
  107  DQ4_B  BI  = M_A_CPU0_SB_DQ<4>
  108  VSS47  POWER  = GND
  109  DQ5_B  BI  = M_A_CPU0_SB_DQ<5>
  110  VSS48  POWER  = GND
  111  DQ8_B  BI  = M_A_CPU0_SB_DQ<8>
  112  VSS49  POWER  = GND
  113  DQ9_B  BI  = M_A_CPU0_SB_DQ<9>
  114  VSS50  POWER  = GND
  115  DQS1_B_T  BI  = M_A_CPU0_SB_DQS_DP<1>
  116  DQS1_B_C  BI  = M_A_CPU0_SB_DQS_DN<1>
  117  VSS51  POWER  = GND
  118  DQ12_B  BI  = M_A_CPU0_SB_DQ<12>
  119  VSS52  POWER  = GND
  120  DQ13_B  BI  = M_A_CPU0_SB_DQ<13>
  121  VSS53  POWER  = GND
  122  DQ16_B  BI  = M_A_CPU0_SB_DQ<16>
  123  VSS54  POWER  = GND
  124  DQ17_B  BI  = M_A_CPU0_SB_DQ<17>
  125  VSS55  POWER  = GND
  126  DQS2_B_T  BI  = M_A_CPU0_SB_DQS_DP<2>
  127  DQS2_B_C  BI  = M_A_CPU0_SB_DQS_DN<2>
  128  VSS56  POWER  = GND
  129  DQ20_B  BI  = M_A_CPU0_SB_DQ<20>
  130  VSS57  POWER  = GND
  131  DQ21_B  BI  = M_A_CPU0_SB_DQ<21>
  132  VSS58  POWER  = GND
  133  DQ24_B  BI  = M_A_CPU0_SB_DQ<24>
  134  VSS59  POWER  = GND
  135  DQ25_B  BI  = M_A_CPU0_SB_DQ<25>
  136  VSS60  POWER  = GND
  137  DQS3_B_T  BI  = M_A_CPU0_SB_DQS_DP<3>
  138  DQS3_B_C  BI  = M_A_CPU0_SB_DQS_DN<3>
  139  VSS61  POWER  = GND
  140  DQ28_B  BI  = M_A_CPU0_SB_DQ<28>
  141  VSS62  POWER  = GND
  142  DQ29_B  BI  = M_A_CPU0_SB_DQ<29>
  143  VSS63  POWER  = GND
  144  RFU1  TRI  = NC
  145  VIN_BULK1  POWER  = P12V_MEM_CPU0
  146  VIN_BULK2  POWER  = P12V_MEM_CPU0
  147  \pwr_good||fail_n\  BI  = PWRGD_CHA_CPU0_DIMM0
  148  HAS  IN  = PD_CHA_CPU0_DIMM0_SAA
  149  RFU2  TRI  = NC
  150  RFU3  TRI  = NC
  151  VSS64  POWER  = GND
  152  DQ2_A  BI  = M_A_CPU0_SA_DQ<2>
  153  VSS65  POWER  = GND
  154  DQ3_A  BI  = M_A_CPU0_SA_DQ<3>
  155  VSS66  POWER  = GND
  156  \dqs5_a_c||tdqs5_a_c||dqs5_a_t||tdqs5_a_t\  BI  = M_A_CPU0_SA_DQS_DN<5>
  157  \dqs5_a_t||tdqs5_a_t\  BI  = M_A_CPU0_SA_DQS_DP<5>
  158  VSS67  POWER  = GND
  159  DQ6_A  BI  = M_A_CPU0_SA_DQ<6>
  160  VSS68  POWER  = GND
  161  DQ7_A  BI  = M_A_CPU0_SA_DQ<7>
  162  VSS69  POWER  = GND
  163  DQ10_A  BI  = M_A_CPU0_SA_DQ<10>
  164  VSS70  POWER  = GND
  165  DQ11_A  BI  = M_A_CPU0_SA_DQ<11>
  166  VSS71  POWER  = GND
  167  \dqs6_a_c||tdqs6_a_c||dqs6_a_t||tdqs6_a_t\  BI  = M_A_CPU0_SA_DQS_DN<6>
  168  \dqs6_a_t||tdqs6_a_t\  BI  = M_A_CPU0_SA_DQS_DP<6>
  169  VSS72  POWER  = GND
  170  DQ14_A  BI  = M_A_CPU0_SA_DQ<14>
  171  VSS73  POWER  = GND
  172  DQ15_A  BI  = M_A_CPU0_SA_DQ<15>
  173  VSS74  POWER  = GND
  174  DQ18_A  BI  = M_A_CPU0_SA_DQ<18>
  175  VSS75  POWER  = GND
  176  DQ19_A  BI  = M_A_CPU0_SA_DQ<19>
  177  VSS76  POWER  = GND
  178  \dqs7_a_c||tdqs7_a_c\  BI  = M_A_CPU0_SA_DQS_DN<7>
  179  \dqs7_a_t||tdqs7_a_t\  BI  = M_A_CPU0_SA_DQS_DP<7>
  180  VSS77  POWER  = GND
  181  DQ22_A  BI  = M_A_CPU0_SA_DQ<22>
  182  VSS78  POWER  = GND
  183  DQ23_A  BI  = M_A_CPU0_SA_DQ<23>
  184  VSS79  POWER  = GND
  185  DQ26_A  BI  = M_A_CPU0_SA_DQ<26>
  186  VSS80  POWER  = GND
  187  DQ27_A  BI  = M_A_CPU0_SA_DQ<27>
  188  VSS81  POWER  = GND
  189  \dqs8_a_c||tdqs8_a_c\  BI  = M_A_CPU0_SA_DQS_DN<8>
  190  \dqs8_a_t||tdqs8_a_t\  BI  = M_A_CPU0_SA_DQS_DP<8>
  191  VSS82  POWER  = GND
  192  DQ30_A  BI  = M_A_CPU0_SA_DQ<30>
  193  VSS83  POWER  = GND
  194  DQ31_A  BI  = M_A_CPU0_SA_DQ<31>
  195  VSS84  POWER  = GND
  196  CB2_A  BI  = M_A_CPU0_SA_CB<2>
  197  VSS85  POWER  = GND
  198  CB3_A  BI  = M_A_CPU0_SA_CB<3>
  199  VSS86  POWER  = GND
  200  \dqs9_a_c||tdqs9_a_c\  BI  = M_A_CPU0_SA_DQS_DN<9>
  201  \dqs9_a_t||tdqs9_a_t\  BI  = M_A_CPU0_SA_DQS_DP<9>
  202  VSS87  POWER  = GND
  203  CB6_A  BI  = M_A_CPU0_SA_CB<6>
  204  VSS88  POWER  = GND
  205  CB7_A  BI  = M_A_CPU0_SA_CB<7>
  206  VSS89  POWER  = GND
  207  RESET_N  IN  = M_A_CPU0_RESET_N
  208  VSS90  POWER  = GND
  209  CS1_A_N  IN  = M_A_CPU0_SA_CS_N<1>
  210  VSS91  POWER  = GND
  211  CA1_A  IN  = M_A_CPU0_SA_CA<1>
  212  VSS92  POWER  = GND
  213  CA3_A  IN  = M_A_CPU0_SA_CA<3>
  214  VSS93  POWER  = GND
  215  CA5_A  IN  = M_A_CPU0_SA_CA<5>
  216  VSS94  POWER  = GND
  217  CK_T  IN  = M_A_CPU0_CLK_DP<0>
  218  CK_C  IN  = M_A_CPU0_CLK_DN<0>
  219  VSS95  POWER  = GND
  220  RFU4  TRI  = NC
  221  CA1_B  IN  = M_A_CPU0_SB_CA<1>
  222  VSS96  POWER  = GND
  223  CA3_B  IN  = M_A_CPU0_SB_CA<3>
  224  VSS97  POWER  = GND
  225  CA5_B  IN  = M_A_CPU0_SB_CA<5>
  226  VSS98  POWER  = GND
  227  PAR_B  IN  = M_A_CPU0_SB_PAR
  228  VSS99  POWER  = GND
  229  CS1_B_N  IN  = M_A_CPU0_SB_CS_N<1>
  230  VSS100  POWER  = GND
  231  RFU5  TRI  = NC
  232  RFU6  TRI  = NC
  233  VSS101  POWER  = GND
  234  CB6_B  BI  = M_A_CPU0_SB_CB<6>
  235  VSS102  POWER  = GND
  236  CB7_B  BI  = M_A_CPU0_SB_CB<7>
  237  VSS103  POWER  = GND
  238  DQS4_B_C  BI  = M_A_CPU0_SB_DQS_DN<4>
  239  DQS4_B_T  BI  = M_A_CPU0_SB_DQS_DP<4>
  240  VSS104  POWER  = GND
  241  CB2_B  BI  = M_A_CPU0_SB_CB<2>
  242  VSS105  POWER  = GND
  243  CB3_B  BI  = M_A_CPU0_SB_CB<3>
  244  VSS106  POWER  = GND
  245  DQ2_B  BI  = M_A_CPU0_SB_DQ<2>
  246  VSS107  POWER  = GND
  247  DQ3_B  BI  = M_A_CPU0_SB_DQ<3>
  248  VSS108  POWER  = GND
  249  \dqs5_b_c||tdqs5_b_c\  BI  = M_A_CPU0_SB_DQS_DN<5>
  250  \dqs5_b_t||tdqs5_b_t\  BI  = M_A_CPU0_SB_DQS_DP<5>
  251  VSS109  POWER  = GND
  252  DQ6_B  BI  = M_A_CPU0_SB_DQ<6>
  253  VSS110  POWER  = GND
  254  DQ7_B  BI  = M_A_CPU0_SB_DQ<7>
  255  VSS111  POWER  = GND
  256  DQ10_B  BI  = M_A_CPU0_SB_DQ<10>
  257  VSS112  POWER  = GND
  258  DQ11_B  BI  = M_A_CPU0_SB_DQ<11>
  259  VSS113  POWER  = GND
  260  \dqs6_b_c||tdqs6_b_c\  BI  = M_A_CPU0_SB_DQS_DN<6>
  261  \dqs6_b_t||tdqs6_b_t\  BI  = M_A_CPU0_SB_DQS_DP<6>
  262  VSS114  POWER  = GND
  263  DQ14_B  BI  = M_A_CPU0_SB_DQ<14>
  264  VSS115  POWER  = GND
  265  DQ15_B  BI  = M_A_CPU0_SB_DQ<15>
  266  VSS116  POWER  = GND
  267  DQ18_B  BI  = M_A_CPU0_SB_DQ<18>
  268  VSS117  POWER  = GND
  269  DQ19_B  BI  = M_A_CPU0_SB_DQ<19>
  270  VSS118  POWER  = GND
  271  \dqs7_b_c||tdqs7_b_c\  BI  = M_A_CPU0_SB_DQS_DN<7>
  272  \dqs7_b_t||tdqs7_b_t\  BI  = M_A_CPU0_SB_DQS_DP<7>
  273  VSS119  POWER  = GND
  274  DQ22_B  BI  = M_A_CPU0_SB_DQ<22>
  275  VSS120  POWER  = GND
  276  DQ23_B  BI  = M_A_CPU0_SB_DQ<23>
  277  VSS121  POWER  = GND
  278  DQ26_B  BI  = M_A_CPU0_SB_DQ<26>
  279  VSS122  POWER  = GND
  280  DQ27_B  BI  = M_A_CPU0_SB_DQ<27>
  281  VSS123  POWER  = GND
  282  \dqs8_b_c||tdqs8_b_c\  BI  = M_A_CPU0_SB_DQS_DN<8>
  283  \dqs8_b_t||tdqs8_b_t\  BI  = M_A_CPU0_SB_DQS_DP<8>
  284  VSS124  POWER  = GND
  285  DQ30_B  BI  = M_A_CPU0_SB_DQ<30>
  286  VSS125  POWER  = GND
  287  DQ31_B  BI  = M_A_CPU0_SB_DQ<31>
  288  VSS126  POWER  = GND
  G1  G1  POWER  = GND
  G2  G2  POWER  = GND
  G3  G3  POWER  = GND

J5  SCONN8_G802M0083150RD3HR  IO  pkg HEADER2X4SXN  page 27
  1  \1\  BI  = CPU0_XTRIG_R1_L4
  2  \2\  BI  = GND
  3  \3\  BI  = CPU0_XTRIG_R1_L5
  4  \4\  BI  = GND
  5  \5\  BI  = CPU0_XTRIG_R1_L6
  6  \6\  BI  = GND
  7  \7\  BI  = CPU0_XTRIG_R1_L7
  8  \8\  BI  = GND

J6  CONN6_HBC1031L200D8H  CONN6_HBC1031-L200D-8H IO  pkg HEADER2X3XE  page 28
  1  \1\  BI  = CPU0_PWR_BTN_N
  2  \2\  BI  = GND
  3  \3\  BI  = RST_CPU0_SYS_N
  4  \4\  BI  = GND
  5  \5\  BI  = NC
  6  \6\  BI  = GND

J7  SCONN8_G802M0083150RD3HR  IO  pkg HEADER2X4SXN  page 54
  1  \1\  BI  = CPU1_XTRIG_R1_L4
  2  \2\  BI  = GND
  3  \3\  BI  = CPU1_XTRIG_R1_L5
  4  \4\  BI  = GND
  5  \5\  BI  = CPU1_XTRIG_R1_L6
  6  \6\  BI  = GND
  7  \7\  BI  = CPU1_XTRIG_R1_L7
  8  \8\  BI  = GND

J8  CONN4_HFK1040L0P1L7H  CONN4_HFK1040-L0P1L-7H IO  pkg HEADER1X4BHXA  page 151
  1  \1\  BI  = UART_VCC_J8
  2  \2\  BI  = UART_CPU0_SCM_LVC3_UART1_R_RX
  3  \3\  BI  = UART_CPU0_SCM_LVC3_UART1_TX
  4  \4\  BI  = GND

J13  CONN4_HFK1040L0P1L7H  CONN4_HFK1040-L0P1L-7H IO  pkg HEADER1X4BHXA  page 164
  1  \1\  BI  = UART_VCC_J13
  2  \2\  BI  = UART_CPU0_LVC3_UART0_RX
  3  \3\  BI  = UART_CPU0_LVC3_UART0_TX
  4  \4\  BI  = GND
